(kicad_pcb
	(version 20260206)
	(generator "pcbnew")
	(generator_version "10.0")
	(general
		(thickness 1.6)
		(legacy_teardrops no)
	)
	(paper "A4")
	(title_block
		(title "Wiwynn_Tioga_Pass_MB.brd")
		(comment 1 "Tioga Pass / footprints 985-989 of 4770")
	)
	(layers
		(0 "F.Cu" signal "TOP")
		(4 "In1.Cu" signal "L2GND")
		(6 "In2.Cu" signal "L3")
		(8 "In3.Cu" signal "L4GND")
		(10 "In4.Cu" signal "L5")
		(12 "In5.Cu" signal "L6GND")
		(14 "In6.Cu" signal "L7VCC")
		(16 "In7.Cu" signal "L8VCC")
		(18 "In8.Cu" signal "L9GND")
		(20 "In9.Cu" signal "L10")
		(22 "In10.Cu" signal "L11GND")
		(24 "In11.Cu" signal "L12")
		(26 "In12.Cu" signal "L13GND")
		(2 "B.Cu" signal "BOTTOM")
		(9 "F.Adhes" user "F.Adhesive")
		(11 "B.Adhes" user "B.Adhesive")
		(13 "F.Paste" user "Package Geometry/Pastemask Top")
		(15 "B.Paste" user "Package Geometry/Pastemask Bottom")
		(5 "F.SilkS" user "Ref Des/Silkscreen Top")
		(7 "B.SilkS" user "Ref Des/Silkscreen Bottom")
		(1 "F.Mask" user "Board Geometry/Soldermask Top")
		(3 "B.Mask" user "Board Geometry/Soldermask Bottom")
		(17 "Dwgs.User" user "User.Drawings")
		(19 "Cmts.User" user "User.Comments")
		(21 "Eco1.User" user "User.Eco1")
		(23 "Eco2.User" user "User.Eco2")
		(25 "Edge.Cuts" user "Board Geometry/Outline")
		(27 "Margin" user)
		(31 "F.CrtYd" user "Package Geometry/Place Bound Top")
		(29 "B.CrtYd" user "Package Geometry/Place Bound Bottom")
		(35 "F.Fab" user "Ref Des/Assembly Top")
		(33 "B.Fab" user "Ref Des/Assembly Bottom")
	)
	(footprint ""
		(layer "F.Cu")
		(at 93.038168 -3.321812 -90)
		(property "Reference" "C2G15"
			(at 0 0 270)
			(layer "F.SilkS")
			(hide yes)
			(effects
				(font
					(size 1.27 1.27)
				)
			)
		)
		(property "Value" ""
			(at 0 0 270)
			(layer "F.Fab")
			(effects
				(font
					(size 1.27 1.27)
				)
			)
		)
		(duplicate_pad_numbers_are_jumpers no)
		(fp_rect
			(start -0.500126 1.598422)
			(end 0.500126 -0.201422)
			(stroke
				(width 0)
				(type default)
			)
			(fill no)
			(layer "F.CrtYd")
		)
		(fp_line
			(start -0.500126 1.598422)
			(end -0.500126 -0.201422)
			(stroke
				(width 0.1)
				(type default)
			)
			(layer "F.Fab")
		)
		(fp_line
			(start 0.500126 1.598422)
			(end -0.500126 1.598422)
			(stroke
				(width 0.1)
				(type default)
			)
			(layer "F.Fab")
		)
		(fp_line
			(start -0.500126 -0.201422)
			(end 0.500126 -0.201422)
			(stroke
				(width 0.1)
				(type default)
			)
			(layer "F.Fab")
		)
		(fp_line
			(start 0.500126 -0.201422)
			(end 0.500126 1.598422)
			(stroke
				(width 0.1)
				(type default)
			)
			(layer "F.Fab")
		)
		(pad "1" smd rect
			(at 0 0 180)
			(size 0.889 0.9906)
			(layers "F.Cu" "F.Mask" "F.Paste")
			(net "PVDDQ_GHJ")
		)
		(pad "2" smd rect
			(at 0 1.397 180)
			(size 0.889 0.9906)
			(layers "F.Cu" "F.Mask" "F.Paste")
			(net "GND")
		)
		(zone
			(layer "F.Cu")
			(hatch none 0.5)
			(connect_pads
				(clearance 0)
			)
			(min_thickness 0.25)
			(keepout
				(tracks not_allowed)
				(vias allowed)
				(pads allowed)
				(copperpour not_allowed)
				(footprints allowed)
			)
			(placement
				(enabled no)
				(sheetname "")
			)
			(fill
				(thermal_gap 0.5)
				(thermal_bridge_width 0.5)
				(island_removal_mode 0)
			)
			(polygon
				(pts
					(xy 92.085668 -3.817112) (xy 92.085668 -2.826512) (xy 92.593668 -2.826512) (xy 92.593668 -3.817112)
				)
			)
		)
		(zone
			(layer "F.Cu")
			(hatch none 0.5)
			(connect_pads
				(clearance 0)
			)
			(min_thickness 0.25)
			(keepout
				(tracks allowed)
				(vias not_allowed)
				(pads allowed)
				(copperpour not_allowed)
				(footprints allowed)
			)
			(placement
				(enabled no)
				(sheetname "")
			)
			(fill
				(thermal_gap 0.5)
				(thermal_bridge_width 0.5)
				(island_removal_mode 0)
			)
			(polygon
				(pts
					(xy 92.085668 -3.817112) (xy 92.085668 -2.826512) (xy 92.593668 -2.826512) (xy 92.593668 -3.817112)
				)
			)
		)
	)
	(footprint ""
		(layer "F.Cu")
		(at 478.1931 -42.9514 -90)
		(property "Reference" "R9E16"
			(at 0 0 270)
			(layer "F.SilkS")
			(hide yes)
			(effects
				(font
					(size 1.27 1.27)
				)
			)
		)
		(property "Value" ""
			(at 0 0 270)
			(layer "F.Fab")
			(effects
				(font
					(size 1.27 1.27)
				)
			)
		)
		(duplicate_pad_numbers_are_jumpers no)
		(fp_poly
			(pts
				(xy -0.2794 -0.1016) (xy 0.2794 -0.1016) (xy 0.2794 0.9906) (xy -0.2794 0.9906)
			)
			(stroke
				(width 0)
				(type default)
			)
			(fill no)
			(layer "F.CrtYd")
		)
		(fp_line
			(start -0.2794 0.9906)
			(end 0.2794 0.9906)
			(stroke
				(width 0.1)
				(type default)
			)
			(layer "F.Fab")
		)
		(fp_line
			(start 0.2794 0.9906)
			(end 0.2794 -0.1016)
			(stroke
				(width 0.1)
				(type default)
			)
			(layer "F.Fab")
		)
		(fp_line
			(start -0.2794 -0.1016)
			(end -0.2794 0.9906)
			(stroke
				(width 0.1)
				(type default)
			)
			(layer "F.Fab")
		)
		(fp_line
			(start 0.2794 -0.1016)
			(end -0.2794 -0.1016)
			(stroke
				(width 0.1)
				(type default)
			)
			(layer "F.Fab")
		)
		(pad "1" smd rect
			(at 0 0 270)
			(size 0.508 0.508)
			(layers "F.Cu" "F.Mask" "F.Paste")
			(net "RMII_PCH_SPRNGVLLE_ARB_IN_R")
		)
		(pad "2" smd rect
			(at 0 0.889 270)
			(size 0.508 0.508)
			(layers "F.Cu" "F.Mask" "F.Paste")
			(net "RMII_PCH_SPRNGVLLE_ARB_IN")
		)
		(zone
			(layer "F.Cu")
			(hatch none 0.5)
			(connect_pads
				(clearance 0)
			)
			(min_thickness 0.25)
			(keepout
				(tracks not_allowed)
				(vias allowed)
				(pads allowed)
				(copperpour not_allowed)
				(footprints allowed)
			)
			(placement
				(enabled no)
				(sheetname "")
			)
			(fill
				(thermal_gap 0.5)
				(thermal_bridge_width 0.5)
				(island_removal_mode 0)
			)
			(polygon
				(pts
					(xy 477.5581 -43.2054) (xy 477.5581 -42.6974) (xy 477.9391 -42.6974) (xy 477.9391 -43.2054)
				)
			)
		)
		(zone
			(layer "F.Cu")
			(hatch none 0.5)
			(connect_pads
				(clearance 0)
			)
			(min_thickness 0.25)
			(keepout
				(tracks allowed)
				(vias not_allowed)
				(pads allowed)
				(copperpour not_allowed)
				(footprints allowed)
			)
			(placement
				(enabled no)
				(sheetname "")
			)
			(fill
				(thermal_gap 0.5)
				(thermal_bridge_width 0.5)
				(island_removal_mode 0)
			)
			(polygon
				(pts
					(xy 477.9391 -43.2054) (xy 477.9391 -42.6974) (xy 477.5581 -42.6974) (xy 477.5581 -43.2054)
				)
			)
		)
	)
	(footprint ""
		(layer "F.Cu")
		(at 155.194 -30.5308 -90)
		(property "Reference" "R3F5"
			(at 0 0 270)
			(layer "F.SilkS")
			(hide yes)
			(effects
				(font
					(size 1.27 1.27)
				)
			)
		)
		(property "Value" ""
			(at 0 0 270)
			(layer "F.Fab")
			(effects
				(font
					(size 1.27 1.27)
				)
			)
		)
		(duplicate_pad_numbers_are_jumpers no)
		(fp_poly
			(pts
				(xy -0.2794 -0.1016) (xy 0.2794 -0.1016) (xy 0.2794 0.9906) (xy -0.2794 0.9906)
			)
			(stroke
				(width 0)
				(type default)
			)
			(fill no)
			(layer "F.CrtYd")
		)
		(fp_line
			(start -0.2794 0.9906)
			(end 0.2794 0.9906)
			(stroke
				(width 0.1)
				(type default)
			)
			(layer "F.Fab")
		)
		(fp_line
			(start 0.2794 0.9906)
			(end 0.2794 -0.1016)
			(stroke
				(width 0.1)
				(type default)
			)
			(layer "F.Fab")
		)
		(fp_line
			(start -0.2794 -0.1016)
			(end -0.2794 0.9906)
			(stroke
				(width 0.1)
				(type default)
			)
			(layer "F.Fab")
		)
		(fp_line
			(start 0.2794 -0.1016)
			(end -0.2794 -0.1016)
			(stroke
				(width 0.1)
				(type default)
			)
			(layer "F.Fab")
		)
		(pad "1" smd rect
			(at 0 0 270)
			(size 0.508 0.508)
			(layers "F.Cu" "F.Mask" "F.Paste")
			(net "CLK_322M_156M_CPU1_OSC_VRM_DN")
		)
		(pad "2" smd rect
			(at 0 0.889 270)
			(size 0.508 0.508)
			(layers "F.Cu" "F.Mask" "F.Paste")
			(net "CLK_322M_OSC_CPU1_RC_DN")
		)
		(zone
			(layer "F.Cu")
			(hatch none 0.5)
			(connect_pads
				(clearance 0)
			)
			(min_thickness 0.25)
			(keepout
				(tracks not_allowed)
				(vias allowed)
				(pads allowed)
				(copperpour not_allowed)
				(footprints allowed)
			)
			(placement
				(enabled no)
				(sheetname "")
			)
			(fill
				(thermal_gap 0.5)
				(thermal_bridge_width 0.5)
				(island_removal_mode 0)
			)
			(polygon
				(pts
					(xy 154.559 -30.7848) (xy 154.559 -30.2768) (xy 154.94 -30.2768) (xy 154.94 -30.7848)
				)
			)
		)
		(zone
			(layer "F.Cu")
			(hatch none 0.5)
			(connect_pads
				(clearance 0)
			)
			(min_thickness 0.25)
			(keepout
				(tracks allowed)
				(vias not_allowed)
				(pads allowed)
				(copperpour not_allowed)
				(footprints allowed)
			)
			(placement
				(enabled no)
				(sheetname "")
			)
			(fill
				(thermal_gap 0.5)
				(thermal_bridge_width 0.5)
				(island_removal_mode 0)
			)
			(polygon
				(pts
					(xy 154.94 -30.7848) (xy 154.94 -30.2768) (xy 154.559 -30.2768) (xy 154.559 -30.7848)
				)
			)
		)
	)
	(footprint ""
		(layer "F.Cu")
		(at 97.72142 -158.1277 -90)
		(property "Reference" "SH8L1"
			(at 0 0 270)
			(layer "F.SilkS")
			(hide yes)
			(effects
				(font
					(size 1.27 1.27)
				)
			)
		)
		(property "Value" ""
			(at 0 0 270)
			(layer "F.Fab")
			(effects
				(font
					(size 1.27 1.27)
				)
			)
		)
		(duplicate_pad_numbers_are_jumpers no)
		(fp_poly
			(pts
				(xy -0.1651 -0.0508) (xy -0.1651 0.5842) (xy 0.1651 0.5842) (xy 0.1651 -0.0508)
			)
			(stroke
				(width 0)
				(type default)
			)
			(fill no)
			(layer "F.CrtYd")
		)
		(fp_line
			(start -0.1651 0.5842)
			(end -0.1651 -0.0508)
			(stroke
				(width 0.1)
				(type default)
			)
			(layer "F.Fab")
		)
		(fp_line
			(start 0.1651 0.5842)
			(end -0.1651 0.5842)
			(stroke
				(width 0.1)
				(type default)
			)
			(layer "F.Fab")
		)
		(fp_line
			(start -0.1651 -0.0508)
			(end 0.1651 -0.0508)
			(stroke
				(width 0.1)
				(type default)
			)
			(layer "F.Fab")
		)
		(fp_line
			(start 0.1651 -0.0508)
			(end 0.1651 0.5842)
			(stroke
				(width 0.1)
				(type default)
			)
			(layer "F.Fab")
		)
		(pad "1" smd custom
			(at 0 0 90)
			(size 0.0762 0.0762)
			(layers "F.Cu" "F.Mask" "F.Paste")
			(net "VR_PVTT_KLM_SNS")
			(options
				(clearance outline)
				(anchor circle)
			)
			(primitives
				(gr_poly
					(pts
						(arc
							(start -0.1524 -0.10795)
							(mid -0.098518 -0.130268)
							(end -0.0762 -0.18415)
						)
						(xy -0.0762 -0.22225) (xy 0.0762 -0.22225)
						(arc
							(start 0.0762 -0.18415)
							(mid 0.098518 -0.130268)
							(end 0.1524 -0.10795)
						)
						(xy 0.1524 0.22225) (xy -0.1524 0.22225)
					)
					(width 0)
					(fill yes)
				)
			)
		)
		(pad "2" smd custom
			(at 0 0.5334 270)
			(size 0.0762 0.0762)
			(layers "F.Cu" "F.Mask" "F.Paste")
			(net "PVTT_KLM")
			(options
				(clearance outline)
				(anchor circle)
			)
			(primitives
				(gr_poly
					(pts
						(arc
							(start -0.1524 -0.10795)
							(mid -0.098518 -0.130268)
							(end -0.0762 -0.18415)
						)
						(xy -0.0762 -0.22225) (xy 0.0762 -0.22225)
						(arc
							(start 0.0762 -0.18415)
							(mid 0.098518 -0.130268)
							(end 0.1524 -0.10795)
						)
						(xy 0.1524 0.22225) (xy -0.1524 0.22225)
					)
					(width 0)
					(fill yes)
				)
			)
		)
	)
	(footprint ""
		(layer "F.Cu")
		(at 280.138124 -71.714614 180)
		(property "Reference" "C6D10"
			(at 0 0 180)
			(layer "F.SilkS")
			(hide yes)
			(effects
				(font
					(size 1.27 1.27)
				)
			)
		)
		(property "Value" ""
			(at 0 0 180)
			(layer "F.Fab")
			(effects
				(font
					(size 1.27 1.27)
				)
			)
		)
		(duplicate_pad_numbers_are_jumpers no)
		(fp_poly
			(pts
				(xy -0.4953 -0.2032) (xy 0.4953 -0.2032) (xy 0.4953 1.6002) (xy -0.4953 1.6002)
			)
			(stroke
				(width 0)
				(type default)
			)
			(fill no)
			(layer "F.CrtYd")
		)
		(fp_line
			(start 0.4953 1.6002)
			(end -0.4953 1.6002)
			(stroke
				(width 0.1)
				(type default)
			)
			(layer "F.Fab")
		)
		(fp_line
			(start 0.4953 -0.2032)
			(end 0.4953 1.6002)
			(stroke
				(width 0.1)
				(type default)
			)
			(layer "F.Fab")
		)
		(fp_line
			(start -0.4953 1.6002)
			(end -0.4953 -0.2032)
			(stroke
				(width 0.1)
				(type default)
			)
			(layer "F.Fab")
		)
		(fp_line
			(start -0.4953 -0.2032)
			(end 0.4953 -0.2032)
			(stroke
				(width 0.1)
				(type default)
			)
			(layer "F.Fab")
		)
		(pad "1" smd rect
			(at 0 0 180)
			(size 0.762 0.889)
			(layers "F.Cu" "F.Mask" "F.Paste")
			(net "PVCCIO_CPU0")
		)
		(pad "2" smd rect
			(at 0 1.397 180)
			(size 0.762 0.889)
			(layers "F.Cu" "F.Mask" "F.Paste")
			(net "GND")
		)
		(zone
			(layer "F.Cu")
			(hatch none 0.5)
			(connect_pads
				(clearance 0)
			)
			(min_thickness 0.25)
			(keepout
				(tracks not_allowed)
				(vias allowed)
				(pads allowed)
				(copperpour not_allowed)
				(footprints allowed)
			)
			(placement
				(enabled no)
				(sheetname "")
			)
			(fill
				(thermal_gap 0.5)
				(thermal_bridge_width 0.5)
				(island_removal_mode 0)
			)
			(polygon
				(pts
					(xy 280.519124 -72.159114) (xy 279.757124 -72.159114) (xy 279.757124 -72.667114) (xy 280.519124 -72.667114)
				)
			)
		)
	)
)
